(kicad_pcb
	(version 20260206)
	(generator "pcbnew")
	(generator_version "10.0")
	(general
		(thickness 1.6)
		(legacy_teardrops no)
	)
	(paper "A4")
	(title_block
		(title "Bryce Canyon_Front Panel_16369-1_OCP.brd")
		(comment 1 "Bryce Canyon / footprints 1-7 of 154")
	)
	(layers
		(0 "F.Cu" signal "TOP")
		(4 "In1.Cu" signal "L2GND")
		(6 "In2.Cu" signal "L3VCC")
		(2 "B.Cu" signal "BOTTOM")
		(9 "F.Adhes" user "F.Adhesive")
		(11 "B.Adhes" user "B.Adhesive")
		(13 "F.Paste" user "Package Geometry/Pastemask Top")
		(15 "B.Paste" user "Package Geometry/Pastemask Bottom")
		(5 "F.SilkS" user "Ref Des/Silkscreen Top")
		(7 "B.SilkS" user "Ref Des/Silkscreen Bottom")
		(1 "F.Mask" user "Board Geometry/Soldermask Top")
		(3 "B.Mask" user "Board Geometry/Soldermask Bottom")
		(17 "Dwgs.User" user "User.Drawings")
		(19 "Cmts.User" user "User.Comments")
		(21 "Eco1.User" user "User.Eco1")
		(23 "Eco2.User" user "User.Eco2")
		(25 "Edge.Cuts" user "Board Geometry/Outline")
		(27 "Margin" user)
		(31 "F.CrtYd" user "Package Geometry/Place Bound Top")
		(29 "B.CrtYd" user "Package Geometry/Place Bound Bottom")
		(35 "F.Fab" user "Ref Des/Assembly Top")
		(33 "B.Fab" user "Ref Des/Assembly Bottom")
	)
	(footprint ""
		(layer "F.Cu")
		(at 11.811 -47.65294 90)
		(property "Reference" "R28"
			(at 0 0 90)
			(layer "F.SilkS")
			(hide yes)
			(effects
				(font
					(size 1.27 1.27)
				)
			)
		)
		(property "Value" "4K7R2F-GP"
			(at 0.064008 -4.679696 90)
			(unlocked yes)
			(layer "F.Fab")
			(hide yes)
			(effects
				(font
					(size 2.54 2.54)
					(thickness 0.381)
				)
			)
		)
		(property "Device Type" "R402H16"
			(at 0.064008 -6.203696 90)
			(unlocked yes)
			(layer "F.Fab")
			(hide yes)
			(effects
				(font
					(size 2.54 2.54)
					(thickness 0.381)
				)
			)
		)
		(duplicate_pad_numbers_are_jumpers no)
		(fp_line
			(start 0.508 -0.9398)
			(end -0.508 -0.9398)
			(stroke
				(width 0.1524)
				(type default)
			)
			(layer "F.SilkS")
		)
		(fp_line
			(start -0.508 -0.9398)
			(end -0.508 0.9398)
			(stroke
				(width 0.1524)
				(type default)
			)
			(layer "F.SilkS")
		)
		(fp_rect
			(start -0.508 0.9398)
			(end 0.508 -0.9398)
			(stroke
				(width 0)
				(type default)
			)
			(fill no)
			(layer "F.CrtYd")
		)
		(fp_rect
			(start -0.508 0.9398)
			(end 0.508 -0.9398)
			(stroke
				(width 0)
				(type default)
			)
			(fill no)
			(layer "F.Fab")
		)
		(pad "1" smd custom
			(at 0 -0.4445 90)
			(size 0.1397 0.1397)
			(layers "F.Cu" "F.Mask" "F.Paste")
			(net "TEMP_1_A1")
			(options
				(clearance outline)
				(anchor circle)
			)
			(primitives
				(gr_poly
					(pts
						(arc
							(start -0.1778 -0.2794)
							(mid -0.249642 -0.249642)
							(end -0.2794 -0.1778)
						)
						(arc
							(start -0.2794 0.1778)
							(mid -0.249642 0.249642)
							(end -0.1778 0.2794)
						)
						(arc
							(start 0.1778 0.2794)
							(mid 0.249642 0.249642)
							(end 0.2794 0.1778)
						)
						(arc
							(start 0.2794 -0.1778)
							(mid 0.249642 -0.249642)
							(end 0.1778 -0.2794)
						)
					)
					(width 0)
					(fill yes)
				)
			)
		)
		(pad "2" smd custom
			(at 0 0.4445 90)
			(size 0.1397 0.1397)
			(layers "F.Cu" "F.Mask" "F.Paste")
			(net "GND")
			(options
				(clearance outline)
				(anchor circle)
			)
			(primitives
				(gr_poly
					(pts
						(arc
							(start -0.1778 -0.2794)
							(mid -0.249642 -0.249642)
							(end -0.2794 -0.1778)
						)
						(arc
							(start -0.2794 0.1778)
							(mid -0.249642 0.249642)
							(end -0.1778 0.2794)
						)
						(arc
							(start 0.1778 0.2794)
							(mid 0.249642 0.249642)
							(end 0.2794 0.1778)
						)
						(arc
							(start 0.2794 -0.1778)
							(mid 0.249642 -0.249642)
							(end 0.1778 -0.2794)
						)
					)
					(width 0)
					(fill yes)
				)
			)
		)
	)
	(footprint ""
		(layer "F.Cu")
		(at 1.8288 -51.054)
		(property "Reference" "R30"
			(at 0 0 0)
			(layer "F.SilkS")
			(hide yes)
			(effects
				(font
					(size 1.27 1.27)
				)
			)
		)
		(property "Value" "0R2J-2-GP"
			(at 0.064008 -4.679696 0)
			(unlocked yes)
			(layer "F.Fab")
			(hide yes)
			(effects
				(font
					(size 2.54 2.54)
					(thickness 0.381)
				)
			)
		)
		(property "Device Type" "R402H16"
			(at 0.064008 -6.203696 0)
			(unlocked yes)
			(layer "F.Fab")
			(hide yes)
			(effects
				(font
					(size 2.54 2.54)
					(thickness 0.381)
				)
			)
		)
		(duplicate_pad_numbers_are_jumpers no)
		(fp_line
			(start -0.508 -0.9398)
			(end -0.508 0.9398)
			(stroke
				(width 0.1524)
				(type default)
			)
			(layer "F.SilkS")
		)
		(fp_line
			(start 0.508 -0.9398)
			(end -0.508 -0.9398)
			(stroke
				(width 0.1524)
				(type default)
			)
			(layer "F.SilkS")
		)
		(fp_rect
			(start -0.508 0.9398)
			(end 0.508 -0.9398)
			(stroke
				(width 0)
				(type default)
			)
			(fill no)
			(layer "F.CrtYd")
		)
		(fp_rect
			(start -0.508 0.9398)
			(end 0.508 -0.9398)
			(stroke
				(width 0)
				(type default)
			)
			(fill no)
			(layer "F.Fab")
		)
		(pad "1" smd custom
			(at 0 -0.4445)
			(size 0.1397 0.1397)
			(layers "F.Cu" "F.Mask" "F.Paste")
			(net "TEMP_1_SCL")
			(options
				(clearance outline)
				(anchor circle)
			)
			(primitives
				(gr_poly
					(pts
						(arc
							(start -0.1778 -0.2794)
							(mid -0.249642 -0.249642)
							(end -0.2794 -0.1778)
						)
						(arc
							(start -0.2794 0.1778)
							(mid -0.249642 0.249642)
							(end -0.1778 0.2794)
						)
						(arc
							(start 0.1778 0.2794)
							(mid 0.249642 0.249642)
							(end 0.2794 0.1778)
						)
						(arc
							(start 0.2794 -0.1778)
							(mid 0.249642 -0.249642)
							(end 0.1778 -0.2794)
						)
					)
					(width 0)
					(fill yes)
				)
			)
		)
		(pad "2" smd custom
			(at 0 0.4445)
			(size 0.1397 0.1397)
			(layers "F.Cu" "F.Mask" "F.Paste")
			(net "I2C_DPB_A_SCL")
			(options
				(clearance outline)
				(anchor circle)
			)
			(primitives
				(gr_poly
					(pts
						(arc
							(start -0.1778 -0.2794)
							(mid -0.249642 -0.249642)
							(end -0.2794 -0.1778)
						)
						(arc
							(start -0.2794 0.1778)
							(mid -0.249642 0.249642)
							(end -0.1778 0.2794)
						)
						(arc
							(start 0.1778 0.2794)
							(mid 0.249642 0.249642)
							(end 0.2794 0.1778)
						)
						(arc
							(start 0.2794 -0.1778)
							(mid 0.249642 -0.249642)
							(end 0.1778 -0.2794)
						)
					)
					(width 0)
					(fill yes)
				)
			)
		)
	)
	(footprint ""
		(layer "F.Cu")
		(at 7.3914 -49.022 -90)
		(property "Reference" "U7"
			(at 0 0 270)
			(layer "F.SilkS")
			(hide yes)
			(effects
				(font
					(size 1.27 1.27)
				)
			)
		)
		(property "Value" "TMP75AIDGKR-GP"
			(at -0.1143 -9.1948 270)
			(unlocked yes)
			(layer "F.Fab")
			(hide yes)
			(effects
				(font
					(size 1.016 1.016)
					(thickness 0.1524)
				)
			)
		)
		(property "Device Type" "MSOP8-1H44"
			(at -0.1143 -10.795 270)
			(unlocked yes)
			(layer "F.Fab")
			(hide yes)
			(effects
				(font
					(size 1.016 1.016)
					(thickness 0.1524)
				)
			)
		)
		(duplicate_pad_numbers_are_jumpers no)
		(fp_line
			(start -1.778 1.0922)
			(end -1.778 3.048)
			(stroke
				(width 0.508)
				(type default)
			)
			(layer "F.SilkS")
		)
		(fp_line
			(start -1.9558 1.016)
			(end 1.0795 1.016)
			(stroke
				(width 0.1524)
				(type default)
			)
			(layer "F.SilkS")
		)
		(fp_line
			(start 1.0795 1.016)
			(end 1.0795 -1.016)
			(stroke
				(width 0.1524)
				(type default)
			)
			(layer "F.SilkS")
		)
		(fp_line
			(start -1.4478 -0.0381)
			(end -1.9558 0.4699)
			(stroke
				(width 0.1524)
				(type default)
			)
			(layer "F.SilkS")
		)
		(fp_line
			(start -1.9558 -0.5461)
			(end -1.4478 -0.0381)
			(stroke
				(width 0.1524)
				(type default)
			)
			(layer "F.SilkS")
		)
		(fp_line
			(start -1.9558 -1.016)
			(end -1.9558 1.016)
			(stroke
				(width 0.1524)
				(type default)
			)
			(layer "F.SilkS")
		)
		(fp_line
			(start 1.0795 -1.016)
			(end -1.9558 -1.016)
			(stroke
				(width 0.1524)
				(type default)
			)
			(layer "F.SilkS")
		)
		(fp_poly
			(pts
				(xy -1.1557 -1.016) (xy -1.1557 1.016) (xy 1.1557 1.016) (xy 1.1557 -1.016)
			)
			(stroke
				(width 0)
				(type default)
			)
			(fill yes)
			(layer "F.SilkS")
		)
		(fp_rect
			(start -1.4986 2.4511)
			(end 1.4986 -2.4511)
			(stroke
				(width 0)
				(type default)
			)
			(fill no)
			(layer "F.CrtYd")
		)
		(fp_poly
			(pts
				(xy -2.032 3.302) (xy -2.032 -3.302) (xy 2.032 -3.302) (xy 2.032 -2.1209) (xy 1.4986 -2.1209) (xy 1.4986 -2.4511)
				(xy -1.4986 -2.4511) (xy -1.4986 2.4511) (xy 1.4986 2.4511) (xy 1.4986 -2.1082) (xy 2.032 -2.1082)
				(xy 2.032 3.302)
			)
			(stroke
				(width 0)
				(type default)
			)
			(fill no)
			(layer "F.CrtYd")
		)
		(fp_rect
			(start -2.032 3.302)
			(end 2.032 -3.302)
			(stroke
				(width 0)
				(type default)
			)
			(fill no)
			(layer "F.Fab")
		)
		(pad "1" smd rect
			(at -0.97536 2.05486 270)
			(size 0.3556 1.524)
			(layers "F.Cu" "F.Mask" "F.Paste")
			(net "TEMP_1_SDA")
		)
		(pad "2" smd rect
			(at -0.32512 2.05486 270)
			(size 0.3556 1.524)
			(layers "F.Cu" "F.Mask" "F.Paste")
			(net "TEMP_1_SCL")
		)
		(pad "3" smd rect
			(at 0.32512 2.05486 270)
			(size 0.3556 1.524)
			(layers "F.Cu" "F.Mask" "F.Paste")
			(net "TEMP_1_ALERT")
		)
		(pad "4" smd rect
			(at 0.97536 2.05486 270)
			(size 0.3556 1.524)
			(layers "F.Cu" "F.Mask" "F.Paste")
			(net "GND")
		)
		(pad "5" smd rect
			(at 0.97536 -2.05486 270)
			(size 0.3556 1.524)
			(layers "F.Cu" "F.Mask" "F.Paste")
			(net "TEMP_1_A2")
		)
		(pad "6" smd rect
			(at 0.32512 -2.05486 270)
			(size 0.3556 1.524)
			(layers "F.Cu" "F.Mask" "F.Paste")
			(net "TEMP_1_A1")
		)
		(pad "7" smd rect
			(at -0.32512 -2.05486 270)
			(size 0.3556 1.524)
			(layers "F.Cu" "F.Mask" "F.Paste")
			(net "TEMP_1_A0")
		)
		(pad "8" smd rect
			(at -0.97536 -2.05486 270)
			(size 0.3556 1.524)
			(layers "F.Cu" "F.Mask" "F.Paste")
			(net "P3V3_STBY_A")
		)
	)
	(footprint ""
		(layer "F.Cu")
		(at 50.23104 -13.976858)
		(property "Reference" "C10"
			(at 0 0 0)
			(layer "F.SilkS")
			(hide yes)
			(effects
				(font
					(size 1.27 1.27)
				)
			)
		)
		(property "Value" "SCD1U16V2KX-3GP"
			(at 1.1811 -3.3909 0)
			(unlocked yes)
			(layer "F.Fab")
			(hide yes)
			(effects
				(font
					(size 2.54 2.54)
					(thickness 0.381)
				)
			)
		)
		(property "Device Type" "C402H22"
			(at 1.1811 -4.9149 0)
			(unlocked yes)
			(layer "F.Fab")
			(hide yes)
			(effects
				(font
					(size 2.54 2.54)
					(thickness 0.381)
				)
			)
		)
		(duplicate_pad_numbers_are_jumpers no)
		(fp_rect
			(start -0.4318 0.9525)
			(end 0.4318 -0.9525)
			(stroke
				(width 0)
				(type default)
			)
			(fill no)
			(layer "F.CrtYd")
		)
		(fp_rect
			(start -0.4318 0.9525)
			(end 0.4318 -0.9525)
			(stroke
				(width 0)
				(type default)
			)
			(fill no)
			(layer "F.Fab")
		)
		(pad "1" smd custom
			(at 0 -0.4445)
			(size 0.1524 0.1524)
			(layers "F.Cu" "F.Mask" "F.Paste")
			(net "P3V3_STBY_B")
			(options
				(clearance outline)
				(anchor circle)
			)
			(primitives
				(gr_poly
					(pts
						(arc
							(start 0.3048 -0.2032)
							(mid 0.275042 -0.275042)
							(end 0.2032 -0.3048)
						)
						(arc
							(start -0.2032 -0.3048)
							(mid -0.275042 -0.275042)
							(end -0.3048 -0.2032)
						)
						(arc
							(start -0.3048 0.2032)
							(mid -0.275042 0.275042)
							(end -0.2032 0.3048)
						)
						(arc
							(start 0.2032 0.3048)
							(mid 0.275042 0.275042)
							(end 0.3048 0.2032)
						)
					)
					(width 0)
					(fill yes)
				)
			)
		)
		(pad "2" smd custom
			(at 0 0.4445)
			(size 0.1524 0.1524)
			(layers "F.Cu" "F.Mask" "F.Paste")
			(net "GND")
			(options
				(clearance outline)
				(anchor circle)
			)
			(primitives
				(gr_poly
					(pts
						(arc
							(start 0.3048 -0.2032)
							(mid 0.275042 -0.275042)
							(end 0.2032 -0.3048)
						)
						(arc
							(start -0.2032 -0.3048)
							(mid -0.275042 -0.275042)
							(end -0.3048 -0.2032)
						)
						(arc
							(start -0.3048 0.2032)
							(mid -0.275042 0.275042)
							(end -0.2032 0.3048)
						)
						(arc
							(start 0.2032 0.3048)
							(mid 0.275042 0.275042)
							(end 0.3048 0.2032)
						)
					)
					(width 0)
					(fill yes)
				)
			)
		)
	)
	(footprint ""
		(layer "F.Cu")
		(at 27.9146 -6.3246 90)
		(property "Reference" "R16"
			(at 0 0 90)
			(layer "F.SilkS")
			(hide yes)
			(effects
				(font
					(size 1.27 1.27)
				)
			)
		)
		(property "Value" "0R2J-2-GP"
			(at 0.064008 -3.993896 90)
			(unlocked yes)
			(layer "F.Fab")
			(hide yes)
			(effects
				(font
					(size 1.016 1.016)
					(thickness 0.1524)
				)
			)
		)
		(property "Device Type" "R402H16"
			(at 0.064008 -5.517896 90)
			(unlocked yes)
			(layer "F.Fab")
			(hide yes)
			(effects
				(font
					(size 1.016 1.016)
					(thickness 0.1524)
				)
			)
		)
		(duplicate_pad_numbers_are_jumpers no)
		(fp_line
			(start 0.508 -0.9398)
			(end -0.508 -0.9398)
			(stroke
				(width 0.1524)
				(type default)
			)
			(layer "F.SilkS")
		)
		(fp_line
			(start -0.508 -0.9398)
			(end -0.508 0.9398)
			(stroke
				(width 0.1524)
				(type default)
			)
			(layer "F.SilkS")
		)
		(fp_rect
			(start -0.508 0.9398)
			(end 0.508 -0.9398)
			(stroke
				(width 0)
				(type default)
			)
			(fill no)
			(layer "F.CrtYd")
		)
		(fp_rect
			(start -0.508 0.9398)
			(end 0.508 -0.9398)
			(stroke
				(width 0)
				(type default)
			)
			(fill no)
			(layer "F.Fab")
		)
		(pad "1" smd custom
			(at 0 -0.4445 90)
			(size 0.1397 0.1397)
			(layers "F.Cu" "F.Mask" "F.Paste")
			(net "D_FLIP_A_D")
			(options
				(clearance outline)
				(anchor circle)
			)
			(primitives
				(gr_poly
					(pts
						(arc
							(start -0.1778 -0.2794)
							(mid -0.249642 -0.249642)
							(end -0.2794 -0.1778)
						)
						(arc
							(start -0.2794 0.1778)
							(mid -0.249642 0.249642)
							(end -0.1778 0.2794)
						)
						(arc
							(start 0.1778 0.2794)
							(mid 0.249642 0.249642)
							(end 0.2794 0.1778)
						)
						(arc
							(start 0.2794 -0.1778)
							(mid 0.249642 -0.249642)
							(end 0.1778 -0.2794)
						)
					)
					(width 0)
					(fill yes)
				)
			)
		)
		(pad "2" smd custom
			(at 0 0.4445 90)
			(size 0.1397 0.1397)
			(layers "F.Cu" "F.Mask" "F.Paste")
			(net "D_FLIP_A_Q#")
			(options
				(clearance outline)
				(anchor circle)
			)
			(primitives
				(gr_poly
					(pts
						(arc
							(start -0.1778 -0.2794)
							(mid -0.249642 -0.249642)
							(end -0.2794 -0.1778)
						)
						(arc
							(start -0.2794 0.1778)
							(mid -0.249642 0.249642)
							(end -0.1778 0.2794)
						)
						(arc
							(start 0.1778 0.2794)
							(mid 0.249642 0.249642)
							(end 0.2794 0.1778)
						)
						(arc
							(start 0.2794 -0.1778)
							(mid 0.249642 -0.249642)
							(end 0.1778 -0.2794)
						)
					)
					(width 0)
					(fill yes)
				)
			)
		)
	)
	(footprint ""
		(layer "F.Cu")
		(at 33.6804 -9.1186 180)
		(property "Reference" "C30"
			(at 0 0 180)
			(layer "F.SilkS")
			(hide yes)
			(effects
				(font
					(size 1.27 1.27)
				)
			)
		)
		(property "Value" "SCD1U16V2KX-3GP"
			(at 1.1811 -2.7051 180)
			(unlocked yes)
			(layer "F.Fab")
			(hide yes)
			(effects
				(font
					(size 1.016 1.016)
					(thickness 0.1524)
				)
			)
		)
		(property "Device Type" "C402H22"
			(at 1.1811 -4.2291 180)
			(unlocked yes)
			(layer "F.Fab")
			(hide yes)
			(effects
				(font
					(size 1.016 1.016)
					(thickness 0.1524)
				)
			)
		)
		(duplicate_pad_numbers_are_jumpers no)
		(fp_rect
			(start -0.4318 0.9525)
			(end 0.4318 -0.9525)
			(stroke
				(width 0)
				(type default)
			)
			(fill no)
			(layer "F.CrtYd")
		)
		(fp_rect
			(start -0.4318 0.9525)
			(end 0.4318 -0.9525)
			(stroke
				(width 0)
				(type default)
			)
			(fill no)
			(layer "F.Fab")
		)
		(pad "1" smd custom
			(at 0 -0.4445 180)
			(size 0.1524 0.1524)
			(layers "F.Cu" "F.Mask" "F.Paste")
			(net "P3V3_STBY_B")
			(options
				(clearance outline)
				(anchor circle)
			)
			(primitives
				(gr_poly
					(pts
						(arc
							(start 0.3048 -0.2032)
							(mid 0.275042 -0.275042)
							(end 0.2032 -0.3048)
						)
						(arc
							(start -0.2032 -0.3048)
							(mid -0.275042 -0.275042)
							(end -0.3048 -0.2032)
						)
						(arc
							(start -0.3048 0.2032)
							(mid -0.275042 0.275042)
							(end -0.2032 0.3048)
						)
						(arc
							(start 0.2032 0.3048)
							(mid 0.275042 0.275042)
							(end 0.3048 0.2032)
						)
					)
					(width 0)
					(fill yes)
				)
			)
		)
		(pad "2" smd custom
			(at 0 0.4445 180)
			(size 0.1524 0.1524)
			(layers "F.Cu" "F.Mask" "F.Paste")
			(net "GND")
			(options
				(clearance outline)
				(anchor circle)
			)
			(primitives
				(gr_poly
					(pts
						(arc
							(start 0.3048 -0.2032)
							(mid 0.275042 -0.275042)
							(end 0.2032 -0.3048)
						)
						(arc
							(start -0.2032 -0.3048)
							(mid -0.275042 -0.275042)
							(end -0.3048 -0.2032)
						)
						(arc
							(start -0.3048 0.2032)
							(mid -0.275042 0.275042)
							(end -0.2032 0.3048)
						)
						(arc
							(start 0.2032 0.3048)
							(mid 0.275042 0.275042)
							(end 0.3048 0.2032)
						)
					)
					(width 0)
					(fill yes)
				)
			)
		)
	)
	(footprint ""
		(layer "F.Cu")
		(at 2.820162 -59.905138 180)
		(property "Reference" "L1"
			(at 0 0 180)
			(layer "F.SilkS")
			(hide yes)
			(effects
				(font
					(size 1.27 1.27)
				)
			)
		)
		(property "Value" "BLM21PG300SN-2GP"
			(at 0.0254 -6.3754 180)
			(unlocked yes)
			(layer "F.Fab")
			(hide yes)
			(effects
				(font
					(size 2.54 2.54)
					(thickness 0.381)
				)
			)
		)
		(property "Device Type" "L20125H42"
			(at 0.0254 -8.2804 180)
			(unlocked yes)
			(layer "F.Fab")
			(hide yes)
			(effects
				(font
					(size 2.54 2.54)
					(thickness 0.381)
				)
			)
		)
		(duplicate_pad_numbers_are_jumpers no)
		(fp_line
			(start 0.9144 1.7018)
			(end 0.9144 -1.7018)
			(stroke
				(width 0.1524)
				(type default)
			)
			(layer "F.SilkS")
		)
		(fp_line
			(start 0.9144 -1.7018)
			(end -0.9144 -1.7018)
			(stroke
				(width 0.1524)
				(type default)
			)
			(layer "F.SilkS")
		)
		(fp_line
			(start -0.9144 1.7018)
			(end 0.9144 1.7018)
			(stroke
				(width 0.1524)
				(type default)
			)
			(layer "F.SilkS")
		)
		(fp_line
			(start -0.9144 -1.7018)
			(end -0.9144 1.7018)
			(stroke
				(width 0.1524)
				(type default)
			)
			(layer "F.SilkS")
		)
		(fp_rect
			(start -1.0033 1.778)
			(end 1.0033 -1.778)
			(stroke
				(width 0)
				(type default)
			)
			(fill no)
			(layer "F.CrtYd")
		)
		(fp_poly
			(pts
				(xy -1.0033 -1.778) (xy 1.0033 -1.778) (xy 1.0033 1.778) (xy -1.0033 1.778)
			)
			(stroke
				(width 0)
				(type default)
			)
			(fill no)
			(layer "F.Fab")
		)
		(pad "1" smd rect
			(at 0 -0.9652 180)
			(size 1.397 1.143)
			(layers "F.Cu" "F.Mask" "F.Paste")
			(net "P5V_VBUS_A")
		)
		(pad "2" smd rect
			(at 0 0.9652 180)
			(size 1.397 1.143)
			(layers "F.Cu" "F.Mask" "F.Paste")
			(net "P5V_USB_A")
		)
	)
)
